(kicad_pcb
	(version 20260206)
	(generator "pcbnew")
	(generator_version "10.0")
	(general
		(thickness 1.6)
		(legacy_teardrops no)
	)
	(paper "A4")
	(title_block
		(title "Wiwynn_Tioga_Pass_MB.brd")
		(comment 1 "Tioga Pass / footprints 1304-1310 of 4770")
	)
	(layers
		(0 "F.Cu" signal "TOP")
		(4 "In1.Cu" signal "L2GND")
		(6 "In2.Cu" signal "L3")
		(8 "In3.Cu" signal "L4GND")
		(10 "In4.Cu" signal "L5")
		(12 "In5.Cu" signal "L6GND")
		(14 "In6.Cu" signal "L7VCC")
		(16 "In7.Cu" signal "L8VCC")
		(18 "In8.Cu" signal "L9GND")
		(20 "In9.Cu" signal "L10")
		(22 "In10.Cu" signal "L11GND")
		(24 "In11.Cu" signal "L12")
		(26 "In12.Cu" signal "L13GND")
		(2 "B.Cu" signal "BOTTOM")
		(9 "F.Adhes" user "F.Adhesive")
		(11 "B.Adhes" user "B.Adhesive")
		(13 "F.Paste" user "Package Geometry/Pastemask Top")
		(15 "B.Paste" user "Package Geometry/Pastemask Bottom")
		(5 "F.SilkS" user "Ref Des/Silkscreen Top")
		(7 "B.SilkS" user "Ref Des/Silkscreen Bottom")
		(1 "F.Mask" user "Board Geometry/Soldermask Top")
		(3 "B.Mask" user "Board Geometry/Soldermask Bottom")
		(17 "Dwgs.User" user "User.Drawings")
		(19 "Cmts.User" user "User.Comments")
		(21 "Eco1.User" user "User.Eco1")
		(23 "Eco2.User" user "User.Eco2")
		(25 "Edge.Cuts" user "Board Geometry/Outline")
		(27 "Margin" user)
		(31 "F.CrtYd" user "Package Geometry/Place Bound Top")
		(29 "B.CrtYd" user "Package Geometry/Place Bound Bottom")
		(35 "F.Fab" user "Ref Des/Assembly Top")
		(33 "B.Fab" user "Ref Des/Assembly Bottom")
	)
	(footprint ""
		(layer "F.Cu")
		(at 173.355 -8.6995)
		(property "Reference" "C4G8"
			(at 0 0 0)
			(layer "F.SilkS")
			(hide yes)
			(effects
				(font
					(size 1.27 1.27)
				)
			)
		)
		(property "Value" ""
			(at 0 0 0)
			(layer "F.Fab")
			(effects
				(font
					(size 1.27 1.27)
				)
			)
		)
		(duplicate_pad_numbers_are_jumpers no)
		(fp_rect
			(start -0.3048 0.9906)
			(end 0.3048 -0.1016)
			(stroke
				(width 0)
				(type default)
			)
			(fill no)
			(layer "F.CrtYd")
		)
		(fp_line
			(start -0.3048 -0.1016)
			(end -0.3048 0.9906)
			(stroke
				(width 0.1)
				(type default)
			)
			(layer "F.Fab")
		)
		(fp_line
			(start -0.3048 0.9906)
			(end 0.3048 0.9906)
			(stroke
				(width 0.1)
				(type default)
			)
			(layer "F.Fab")
		)
		(fp_line
			(start 0.3048 -0.1016)
			(end -0.3048 -0.1016)
			(stroke
				(width 0.1)
				(type default)
			)
			(layer "F.Fab")
		)
		(fp_line
			(start 0.3048 0.9906)
			(end 0.3048 -0.1016)
			(stroke
				(width 0.1)
				(type default)
			)
			(layer "F.Fab")
		)
		(pad "1" smd rect
			(at 0 0)
			(size 0.508 0.508)
			(layers "F.Cu" "F.Mask" "F.Paste")
			(net "VR_PVPP_GHJ_SS")
		)
		(pad "2" smd rect
			(at 0 0.889)
			(size 0.508 0.508)
			(layers "F.Cu" "F.Mask" "F.Paste")
			(net "AGND_PVPP_GHJ")
		)
		(zone
			(layer "F.Cu")
			(hatch none 0.5)
			(connect_pads
				(clearance 0)
			)
			(min_thickness 0.25)
			(keepout
				(tracks allowed)
				(vias not_allowed)
				(pads allowed)
				(copperpour not_allowed)
				(footprints allowed)
			)
			(placement
				(enabled no)
				(sheetname "")
			)
			(fill
				(thermal_gap 0.5)
				(thermal_bridge_width 0.5)
				(island_removal_mode 0)
			)
			(polygon
				(pts
					(xy 173.101 -8.0645) (xy 173.609 -8.0645) (xy 173.609 -8.4455) (xy 173.101 -8.4455)
				)
			)
		)
		(zone
			(layer "F.Cu")
			(hatch none 0.5)
			(connect_pads
				(clearance 0)
			)
			(min_thickness 0.25)
			(keepout
				(tracks not_allowed)
				(vias allowed)
				(pads allowed)
				(copperpour not_allowed)
				(footprints allowed)
			)
			(placement
				(enabled no)
				(sheetname "")
			)
			(fill
				(thermal_gap 0.5)
				(thermal_bridge_width 0.5)
				(island_removal_mode 0)
			)
			(polygon
				(pts
					(xy 173.101 -8.0645) (xy 173.609 -8.0645) (xy 173.609 -8.4455) (xy 173.101 -8.4455)
				)
			)
		)
	)
	(footprint ""
		(layer "F.Cu")
		(at 166.3446 -26.1747 90)
		(property "Reference" "C4F7"
			(at 2.88163 1.9304 0)
			(unlocked yes)
			(layer "F.SilkS")
			(effects
				(font
					(size 0.7874 0.5842)
					(thickness 0.1524)
				)
				(justify left)
			)
		)
		(property "Value" ""
			(at 0 0 90)
			(layer "F.Fab")
			(effects
				(font
					(size 1.27 1.27)
				)
			)
		)
		(duplicate_pad_numbers_are_jumpers no)
		(fp_line
			(start 2.032 -1.524)
			(end 2.032 1.524)
			(stroke
				(width 0.1524)
				(type default)
			)
			(layer "F.SilkS")
		)
		(fp_line
			(start 1.7272 -1.524)
			(end 2.032 -1.524)
			(stroke
				(width 0.1524)
				(type default)
			)
			(layer "F.SilkS")
		)
		(fp_line
			(start -1.7272 -1.524)
			(end -2.032 -1.524)
			(stroke
				(width 0.1524)
				(type default)
			)
			(layer "F.SilkS")
		)
		(fp_line
			(start -2.032 -1.524)
			(end -2.032 1.524)
			(stroke
				(width 0.1524)
				(type default)
			)
			(layer "F.SilkS")
		)
		(fp_line
			(start 2.2987 -0.2413)
			(end 2.032 -0.2413)
			(stroke
				(width 0.1524)
				(type default)
			)
			(layer "F.SilkS")
		)
		(fp_line
			(start -2.032 -0.2413)
			(end -2.2987 -0.2413)
			(stroke
				(width 0.1524)
				(type default)
			)
			(layer "F.SilkS")
		)
		(fp_line
			(start -2.2987 -0.2413)
			(end -2.2987 7.3533)
			(stroke
				(width 0.1524)
				(type default)
			)
			(layer "F.SilkS")
		)
		(fp_line
			(start 2.032 1.524)
			(end 1.7272 1.524)
			(stroke
				(width 0.1524)
				(type default)
			)
			(layer "F.SilkS")
		)
		(fp_line
			(start -2.032 1.524)
			(end -1.7272 1.524)
			(stroke
				(width 0.1524)
				(type default)
			)
			(layer "F.SilkS")
		)
		(fp_line
			(start 2.2987 7.3533)
			(end 2.2987 -0.2413)
			(stroke
				(width 0.1524)
				(type default)
			)
			(layer "F.SilkS")
		)
		(fp_line
			(start 1.7272 7.3533)
			(end 2.2987 7.3533)
			(stroke
				(width 0.1524)
				(type default)
			)
			(layer "F.SilkS")
		)
		(fp_line
			(start -2.2987 7.3533)
			(end -1.7272 7.3533)
			(stroke
				(width 0.1524)
				(type default)
			)
			(layer "F.SilkS")
		)
		(fp_rect
			(start 2.2987 -0.2413)
			(end -2.2987 7.3533)
			(stroke
				(width 0)
				(type default)
			)
			(fill no)
			(layer "F.CrtYd")
		)
		(fp_line
			(start 2.2987 -0.2413)
			(end 2.2987 7.3533)
			(stroke
				(width 0.1)
				(type default)
			)
			(layer "F.Fab")
		)
		(fp_line
			(start -2.2987 -0.2413)
			(end 2.2987 -0.2413)
			(stroke
				(width 0.1)
				(type default)
			)
			(layer "F.Fab")
		)
		(fp_line
			(start 2.2987 7.3533)
			(end -2.2987 7.3533)
			(stroke
				(width 0.1)
				(type default)
			)
			(layer "F.Fab")
		)
		(fp_line
			(start -2.2987 7.3533)
			(end -2.2987 -0.2413)
			(stroke
				(width 0.1)
				(type default)
			)
			(layer "F.Fab")
		)
		(pad "1" smd rect
			(at 0 0 90)
			(size 2.54 3.048)
			(layers "F.Cu" "F.Mask" "F.Paste")
			(net "PVPP_GHJ")
		)
		(pad "2" smd rect
			(at 0 7.112 90)
			(size 2.54 3.048)
			(layers "F.Cu" "F.Mask" "F.Paste")
			(net "GND")
		)
	)
	(footprint ""
		(layer "F.Cu")
		(at 342.138 -23.749)
		(property "Reference" "C7F10"
			(at 0 0 0)
			(layer "F.SilkS")
			(hide yes)
			(effects
				(font
					(size 1.27 1.27)
				)
			)
		)
		(property "Value" ""
			(at 0 0 0)
			(layer "F.Fab")
			(effects
				(font
					(size 1.27 1.27)
				)
			)
		)
		(duplicate_pad_numbers_are_jumpers no)
		(fp_rect
			(start -0.3048 0.9906)
			(end 0.3048 -0.1016)
			(stroke
				(width 0)
				(type default)
			)
			(fill no)
			(layer "F.CrtYd")
		)
		(fp_line
			(start -0.3048 -0.1016)
			(end -0.3048 0.9906)
			(stroke
				(width 0.1)
				(type default)
			)
			(layer "F.Fab")
		)
		(fp_line
			(start -0.3048 0.9906)
			(end 0.3048 0.9906)
			(stroke
				(width 0.1)
				(type default)
			)
			(layer "F.Fab")
		)
		(fp_line
			(start 0.3048 -0.1016)
			(end -0.3048 -0.1016)
			(stroke
				(width 0.1)
				(type default)
			)
			(layer "F.Fab")
		)
		(fp_line
			(start 0.3048 0.9906)
			(end 0.3048 -0.1016)
			(stroke
				(width 0.1)
				(type default)
			)
			(layer "F.Fab")
		)
		(pad "1" smd rect
			(at 0 0)
			(size 0.508 0.508)
			(layers "F.Cu" "F.Mask" "F.Paste")
			(net "VR_PVPP_ABC_SS")
		)
		(pad "2" smd rect
			(at 0 0.889)
			(size 0.508 0.508)
			(layers "F.Cu" "F.Mask" "F.Paste")
			(net "AGND_PVPP_ABC")
		)
		(zone
			(layer "F.Cu")
			(hatch none 0.5)
			(connect_pads
				(clearance 0)
			)
			(min_thickness 0.25)
			(keepout
				(tracks not_allowed)
				(vias allowed)
				(pads allowed)
				(copperpour not_allowed)
				(footprints allowed)
			)
			(placement
				(enabled no)
				(sheetname "")
			)
			(fill
				(thermal_gap 0.5)
				(thermal_bridge_width 0.5)
				(island_removal_mode 0)
			)
			(polygon
				(pts
					(xy 341.884 -23.114) (xy 342.392 -23.114) (xy 342.392 -23.495) (xy 341.884 -23.495)
				)
			)
		)
		(zone
			(layer "F.Cu")
			(hatch none 0.5)
			(connect_pads
				(clearance 0)
			)
			(min_thickness 0.25)
			(keepout
				(tracks allowed)
				(vias not_allowed)
				(pads allowed)
				(copperpour not_allowed)
				(footprints allowed)
			)
			(placement
				(enabled no)
				(sheetname "")
			)
			(fill
				(thermal_gap 0.5)
				(thermal_bridge_width 0.5)
				(island_removal_mode 0)
			)
			(polygon
				(pts
					(xy 341.884 -23.114) (xy 342.392 -23.114) (xy 342.392 -23.495) (xy 341.884 -23.495)
				)
			)
		)
	)
	(footprint ""
		(layer "F.Cu")
		(at 420.1414 -18.7452)
		(property "Reference" "R9G15"
			(at 0 0 0)
			(layer "F.SilkS")
			(hide yes)
			(effects
				(font
					(size 1.27 1.27)
				)
			)
		)
		(property "Value" ""
			(at 0 0 0)
			(layer "F.Fab")
			(effects
				(font
					(size 1.27 1.27)
				)
			)
		)
		(duplicate_pad_numbers_are_jumpers no)
		(fp_poly
			(pts
				(xy -0.2794 -0.1016) (xy 0.2794 -0.1016) (xy 0.2794 0.9906) (xy -0.2794 0.9906)
			)
			(stroke
				(width 0)
				(type default)
			)
			(fill no)
			(layer "F.CrtYd")
		)
		(fp_line
			(start -0.2794 -0.1016)
			(end -0.2794 0.9906)
			(stroke
				(width 0.1)
				(type default)
			)
			(layer "F.Fab")
		)
		(fp_line
			(start -0.2794 0.9906)
			(end 0.2794 0.9906)
			(stroke
				(width 0.1)
				(type default)
			)
			(layer "F.Fab")
		)
		(fp_line
			(start 0.2794 -0.1016)
			(end -0.2794 -0.1016)
			(stroke
				(width 0.1)
				(type default)
			)
			(layer "F.Fab")
		)
		(fp_line
			(start 0.2794 0.9906)
			(end 0.2794 -0.1016)
			(stroke
				(width 0.1)
				(type default)
			)
			(layer "F.Fab")
		)
		(pad "1" smd rect
			(at 0 0)
			(size 0.508 0.508)
			(layers "F.Cu" "F.Mask" "F.Paste")
			(net "SMB_SENSOR_BMC_STBY_LVC3_SDA")
		)
		(pad "2" smd rect
			(at 0 0.889)
			(size 0.508 0.508)
			(layers "F.Cu" "F.Mask" "F.Paste")
			(net "SMB_SENSOR_STBY_LVC3_SDA")
		)
		(zone
			(layer "F.Cu")
			(hatch none 0.5)
			(connect_pads
				(clearance 0)
			)
			(min_thickness 0.25)
			(keepout
				(tracks allowed)
				(vias not_allowed)
				(pads allowed)
				(copperpour not_allowed)
				(footprints allowed)
			)
			(placement
				(enabled no)
				(sheetname "")
			)
			(fill
				(thermal_gap 0.5)
				(thermal_bridge_width 0.5)
				(island_removal_mode 0)
			)
			(polygon
				(pts
					(xy 419.8874 -18.4912) (xy 420.3954 -18.4912) (xy 420.3954 -18.1102) (xy 419.8874 -18.1102)
				)
			)
		)
		(zone
			(layer "F.Cu")
			(hatch none 0.5)
			(connect_pads
				(clearance 0)
			)
			(min_thickness 0.25)
			(keepout
				(tracks not_allowed)
				(vias allowed)
				(pads allowed)
				(copperpour not_allowed)
				(footprints allowed)
			)
			(placement
				(enabled no)
				(sheetname "")
			)
			(fill
				(thermal_gap 0.5)
				(thermal_bridge_width 0.5)
				(island_removal_mode 0)
			)
			(polygon
				(pts
					(xy 419.8874 -18.1102) (xy 420.3954 -18.1102) (xy 420.3954 -18.4912) (xy 419.8874 -18.4912)
				)
			)
		)
	)
	(footprint ""
		(layer "F.Cu")
		(at 440.817 -143.002 90)
		(property "Reference" "R25W160"
			(at -0.8382 -0.67818 90)
			(unlocked yes)
			(layer "F.SilkS")
			(effects
				(font
					(size 0.4064 0.254)
					(thickness 0.1524)
				)
				(justify left)
			)
		)
		(property "Value" ""
			(at 0 0 90)
			(layer "F.Fab")
			(effects
				(font
					(size 1.27 1.27)
				)
			)
		)
		(duplicate_pad_numbers_are_jumpers no)
		(fp_poly
			(pts
				(xy -0.2794 -0.1016) (xy 0.2794 -0.1016) (xy 0.2794 0.9906) (xy -0.2794 0.9906)
			)
			(stroke
				(width 0)
				(type default)
			)
			(fill no)
			(layer "F.CrtYd")
		)
		(fp_line
			(start 0.2794 -0.1016)
			(end -0.2794 -0.1016)
			(stroke
				(width 0.1)
				(type default)
			)
			(layer "F.Fab")
		)
		(fp_line
			(start -0.2794 -0.1016)
			(end -0.2794 0.9906)
			(stroke
				(width 0.1)
				(type default)
			)
			(layer "F.Fab")
		)
		(fp_line
			(start 0.2794 0.9906)
			(end 0.2794 -0.1016)
			(stroke
				(width 0.1)
				(type default)
			)
			(layer "F.Fab")
		)
		(fp_line
			(start -0.2794 0.9906)
			(end 0.2794 0.9906)
			(stroke
				(width 0.1)
				(type default)
			)
			(layer "F.Fab")
		)
		(pad "1" smd rect
			(at 0 0 90)
			(size 0.508 0.508)
			(layers "F.Cu" "F.Mask" "F.Paste")
			(net "P3V3_STBY")
		)
		(pad "2" smd rect
			(at 0 0.889 90)
			(size 0.508 0.508)
			(layers "F.Cu" "F.Mask" "F.Paste")
			(net "JTAG_BMC_BUF_TDI")
		)
		(zone
			(layer "F.Cu")
			(hatch none 0.5)
			(connect_pads
				(clearance 0)
			)
			(min_thickness 0.25)
			(keepout
				(tracks allowed)
				(vias not_allowed)
				(pads allowed)
				(copperpour not_allowed)
				(footprints allowed)
			)
			(placement
				(enabled no)
				(sheetname "")
			)
			(fill
				(thermal_gap 0.5)
				(thermal_bridge_width 0.5)
				(island_removal_mode 0)
			)
			(polygon
				(pts
					(xy 441.071 -142.748) (xy 441.071 -143.256) (xy 441.452 -143.256) (xy 441.452 -142.748)
				)
			)
		)
		(zone
			(layer "F.Cu")
			(hatch none 0.5)
			(connect_pads
				(clearance 0)
			)
			(min_thickness 0.25)
			(keepout
				(tracks not_allowed)
				(vias allowed)
				(pads allowed)
				(copperpour not_allowed)
				(footprints allowed)
			)
			(placement
				(enabled no)
				(sheetname "")
			)
			(fill
				(thermal_gap 0.5)
				(thermal_bridge_width 0.5)
				(island_removal_mode 0)
			)
			(polygon
				(pts
					(xy 441.452 -142.748) (xy 441.452 -143.256) (xy 441.071 -143.256) (xy 441.071 -142.748)
				)
			)
		)
	)
	(footprint ""
		(layer "F.Cu")
		(at 269.409672 -77.636116)
		(property "Reference" "C5D33"
			(at 0 0 0)
			(layer "F.SilkS")
			(hide yes)
			(effects
				(font
					(size 1.27 1.27)
				)
			)
		)
		(property "Value" ""
			(at 0 0 0)
			(layer "F.Fab")
			(effects
				(font
					(size 1.27 1.27)
				)
			)
		)
		(duplicate_pad_numbers_are_jumpers no)
		(fp_poly
			(pts
				(xy -0.4953 -0.2032) (xy 0.4953 -0.2032) (xy 0.4953 1.6002) (xy -0.4953 1.6002)
			)
			(stroke
				(width 0)
				(type default)
			)
			(fill no)
			(layer "F.CrtYd")
		)
		(fp_line
			(start -0.4953 -0.2032)
			(end 0.4953 -0.2032)
			(stroke
				(width 0.1)
				(type default)
			)
			(layer "F.Fab")
		)
		(fp_line
			(start -0.4953 1.6002)
			(end -0.4953 -0.2032)
			(stroke
				(width 0.1)
				(type default)
			)
			(layer "F.Fab")
		)
		(fp_line
			(start 0.4953 -0.2032)
			(end 0.4953 1.6002)
			(stroke
				(width 0.1)
				(type default)
			)
			(layer "F.Fab")
		)
		(fp_line
			(start 0.4953 1.6002)
			(end -0.4953 1.6002)
			(stroke
				(width 0.1)
				(type default)
			)
			(layer "F.Fab")
		)
		(pad "1" smd rect
			(at 0 0)
			(size 0.762 0.889)
			(layers "F.Cu" "F.Mask" "F.Paste")
			(net "PVCCMCP_CPU0")
		)
		(pad "2" smd rect
			(at 0 1.397)
			(size 0.762 0.889)
			(layers "F.Cu" "F.Mask" "F.Paste")
			(net "GND")
		)
		(zone
			(layer "F.Cu")
			(hatch none 0.5)
			(connect_pads
				(clearance 0)
			)
			(min_thickness 0.25)
			(keepout
				(tracks not_allowed)
				(vias allowed)
				(pads allowed)
				(copperpour not_allowed)
				(footprints allowed)
			)
			(placement
				(enabled no)
				(sheetname "")
			)
			(fill
				(thermal_gap 0.5)
				(thermal_bridge_width 0.5)
				(island_removal_mode 0)
			)
			(polygon
				(pts
					(xy 269.028672 -77.191616) (xy 269.790672 -77.191616) (xy 269.790672 -76.683616) (xy 269.028672 -76.683616)
				)
			)
		)
	)
	(footprint ""
		(layer "F.Cu")
		(at 177.927 -8.255)
		(property "Reference" "R4G11"
			(at 0 0 0)
			(layer "F.SilkS")
			(hide yes)
			(effects
				(font
					(size 1.27 1.27)
				)
			)
		)
		(property "Value" ""
			(at 0 0 0)
			(layer "F.Fab")
			(effects
				(font
					(size 1.27 1.27)
				)
			)
		)
		(duplicate_pad_numbers_are_jumpers no)
		(fp_rect
			(start -0.2794 0.9906)
			(end 0.2794 -0.1016)
			(stroke
				(width 0)
				(type default)
			)
			(fill no)
			(layer "F.CrtYd")
		)
		(fp_line
			(start -0.2794 -0.1016)
			(end -0.2794 0.9906)
			(stroke
				(width 0.1)
				(type default)
			)
			(layer "F.Fab")
		)
		(fp_line
			(start -0.2794 0.9906)
			(end 0.2794 0.9906)
			(stroke
				(width 0.1)
				(type default)
			)
			(layer "F.Fab")
		)
		(fp_line
			(start 0.2794 -0.1016)
			(end -0.2794 -0.1016)
			(stroke
				(width 0.1)
				(type default)
			)
			(layer "F.Fab")
		)
		(fp_line
			(start 0.2794 0.9906)
			(end 0.2794 -0.1016)
			(stroke
				(width 0.1)
				(type default)
			)
			(layer "F.Fab")
		)
		(pad "1" smd rect
			(at 0 0)
			(size 0.508 0.508)
			(layers "F.Cu" "F.Mask" "F.Paste")
			(net "VR_PVPP_GHJ_ISET")
		)
		(pad "2" smd rect
			(at 0 0.889)
			(size 0.508 0.508)
			(layers "F.Cu" "F.Mask" "F.Paste")
			(net "AGND_PVPP_GHJ")
		)
		(zone
			(layer "F.Cu")
			(hatch none 0.5)
			(connect_pads
				(clearance 0)
			)
			(min_thickness 0.25)
			(keepout
				(tracks allowed)
				(vias not_allowed)
				(pads allowed)
				(copperpour not_allowed)
				(footprints allowed)
			)
			(placement
				(enabled no)
				(sheetname "")
			)
			(fill
				(thermal_gap 0.5)
				(thermal_bridge_width 0.5)
				(island_removal_mode 0)
			)
			(polygon
				(pts
					(xy 177.673 -7.62) (xy 178.181 -7.62) (xy 178.181 -8.001) (xy 177.673 -8.001)
				)
			)
		)
		(zone
			(layer "F.Cu")
			(hatch none 0.5)
			(connect_pads
				(clearance 0)
			)
			(min_thickness 0.25)
			(keepout
				(tracks not_allowed)
				(vias allowed)
				(pads allowed)
				(copperpour not_allowed)
				(footprints allowed)
			)
			(placement
				(enabled no)
				(sheetname "")
			)
			(fill
				(thermal_gap 0.5)
				(thermal_bridge_width 0.5)
				(island_removal_mode 0)
			)
			(polygon
				(pts
					(xy 177.673 -7.62) (xy 178.181 -7.62) (xy 178.181 -8.001) (xy 177.673 -8.001)
				)
			)
		)
	)
)
